(kicad_pcb
	(version 20221018)
	(generator pcbnew)
	(general
    (thickness 1.6)
  )
	(paper "A4")
	(title_block
    (title "NUC Computer Cluster Power Breakout HW")
    (date "2023-10-18")
    (rev "1.4.3")
    (company "Antmicro Ltd.")
		(comment 9 "footprints 47-54 of 234")
	)
	(layers
    (0 "F.Cu" mixed)
    (1 "In1.Cu" power)
    (2 "In2.Cu" mixed)
    (31 "B.Cu" power)
    (32 "B.Adhes" user "B.Adhesive")
    (33 "F.Adhes" user "F.Adhesive")
    (34 "B.Paste" user)
    (35 "F.Paste" user)
    (36 "B.SilkS" user "B.Silkscreen")
    (37 "F.SilkS" user "F.Silkscreen")
    (38 "B.Mask" user)
    (39 "F.Mask" user)
    (40 "Dwgs.User" user "User.Drawings")
    (41 "Cmts.User" user "User.Comments")
    (42 "Eco1.User" user "User.Eco1")
    (43 "Eco2.User" user "User.Eco2")
    (44 "Edge.Cuts" user)
    (45 "Margin" user)
    (46 "B.CrtYd" user "B.Courtyard")
    (47 "F.CrtYd" user "F.Courtyard")
    (48 "B.Fab" user)
    (49 "F.Fab" user)
  )
	(footprint "antmicro-footprints:R_0402_1005Metric" (layer "F.Cu")
    (at 165.75 96.5 90)
    (descr "Resistor SMD 0402")
    (tags "resistor SMD 0402")
    (property "Author" "Antmicro")
    (property "Current" "1A")
    (property "DNP" "DNP")
    (property "License" "Apache-2.0")
    (property "MPN" "ERJ2GE0R00X")
    (property "Manufacturer" "Panasonic")
    (property "Sheetfile" "pow-cycl-curr-meas.kicad_sch")
    (property "Sheetname" "Power Cycling & Current Measurement")
    (property "Tolerance" "")
    (property "Val" "0R")
    (property "dnp" "")
    (property "exclude_from_bom" "")
    (property "ki_description" "SMD Chip Resistor, Jumper, 0 ohm, 100 mW, 0402 [1005 Metric], Thick Film, General Purpose")
    (property "ki_keywords" "0402, SMT, RESISTOR, PASSIVE")
    (attr smd exclude_from_bom)
    (fp_text reference "R13" (at 0.85 0.45 90) (layer "F.SilkS")
        (effects (font (size 0.7 0.7) (thickness 0.15)) (justify left bottom))
    )
    (fp_text value "R_0R_0402" (at -1.011843 1.772047 90) (layer "F.Fab")
        (effects (font (size 0.7 0.7) (thickness 0.15)) (justify left bottom))
    )
    (fp_text user "License: Apache-2.0" (at -0.95 5.169 90) (layer "F.Fab") hide
        (effects (font (size 0.7 0.7) (thickness 0.15)) (justify left bottom))
    )
    (fp_text user "Author: Antmicro" (at -0.95 4.169 90) (layer "F.Fab") hide
        (effects (font (size 0.7 0.7) (thickness 0.15)) (justify left bottom))
    )
    (fp_text user "${REFERENCE}" (at -0.95 3.168 90) (layer "F.Fab") hide
        (effects (font (size 0.7 0.7) (thickness 0.15)) (justify left bottom))
    )
    (fp_rect (start -0.925 -0.47) (end 0.925 0.47)
      (stroke (width 0.05) (type default)) (fill none) (layer "F.CrtYd"))
    (fp_rect (start -0.5 -0.25) (end 0.5 0.25)
      (stroke (width 0.15) (type solid)) (fill none) (layer "F.Fab"))
    (pad "1" smd roundrect (at -0.48 0 90) (size 0.59 0.64) (layers "F.Cu" "F.Paste" "F.Mask") (roundrect_rratio 0.25)
      (net 1 "VCC3V3") (pintype "passive"))
    (pad "2" smd roundrect (at 0.48 0 90) (size 0.59 0.64) (layers "F.Cu" "F.Paste" "F.Mask") (roundrect_rratio 0.25)
      (net 105 "Net-(U10-A0)") (pintype "passive"))
  )
	(footprint "antmicro-footprints:R_0402_1005Metric" (layer "F.Cu")
    (at 164.75 92.1 180)
    (descr "Resistor SMD 0402")
    (tags "resistor SMD 0402")
    (property "Author" "Antmicro")
    (property "License" "Apache-2.0")
    (property "MPN" "CR0402-FX-4701GLF")
    (property "Manufacturer" "Bourns")
    (property "Sheetfile" "power-switch.kicad_sch")
    (property "Sheetname" "Power switch 4")
    (property "Tolerance" "1%")
    (property "Val" "4k7")
    (property "ki_description" "SMD Chip Resistor, 4.7 kohm, ± 1%, 62.5 mW, 0402 [1005 Metric], Thick Film, General Purpose")
    (property "ki_keywords" "0402, SMT, RESISTOR, PASSIVE")
    (zone_connect 1)
    (attr smd)
    (fp_text reference "R28" (at 0.05 -1) (layer "F.SilkS")
        (effects (font (size 0.7 0.7) (thickness 0.15)))
    )
    (fp_text value "R_4k7_0402" (at 0 1.17) (layer "F.Fab") hide
        (effects (font (size 1 1) (thickness 0.15)))
    )
    (fp_text user "Author: Antmicro" (at -0.95 4.169) (layer "F.Fab") hide
        (effects (font (size 0.7 0.7) (thickness 0.15)) (justify right bottom))
    )
    (fp_text user "License: Apache-2.0" (at -0.95 5.169) (layer "F.Fab") hide
        (effects (font (size 0.7 0.7) (thickness 0.15)) (justify right bottom))
    )
    (fp_text user "${REFERENCE}" (at 0 0) (layer "F.Fab")
        (effects (font (size 0.7 0.7) (thickness 0.15)))
    )
    (fp_rect (start -0.925 -0.47) (end 0.925 0.47)
      (stroke (width 0.05) (type default)) (fill none) (layer "F.CrtYd"))
    (fp_rect (start -0.5 -0.25) (end 0.5 0.25)
      (stroke (width 0.15) (type solid)) (fill none) (layer "F.Fab"))
    (pad "1" smd roundrect (at -0.48 0 180) (size 0.59 0.64) (layers "F.Cu" "F.Paste" "F.Mask") (roundrect_rratio 0.25)
      (net 11 "VCC12V0") (pintype "passive"))
    (pad "2" smd roundrect (at 0.48 0 180) (size 0.59 0.64) (layers "F.Cu" "F.Paste" "F.Mask") (roundrect_rratio 0.25)
      (net 85 "Net-(D17-A)") (pintype "passive"))
  )
	(footprint "antmicro-footprints:C_0402_1005Metric" (layer "F.Cu")
    (at 176.85 85.6 180)
    (descr "Capacitor SMD 0402")
    (tags "capacitor SMD 0402")
    (property "Author" "Antmicro")
    (property "Dielectric" "X5R")
    (property "License" "Apache-2.0")
    (property "MPN" "GRM155R61H104KE14D")
    (property "Manufacturer" "Murata")
    (property "Sheetfile" "pow-cycl-curr-meas.kicad_sch")
    (property "Sheetname" "Power Cycling & Current Measurement")
    (property "Val" "100n")
    (property "Voltage" "50V")
    (property "ki_description" "SMD Multilayer Ceramic Capacitor, 0.1 µF, 50 V, 0402 [1005 Metric], ± 10%, X5R, GRM Series")
    (property "ki_keywords" "0402, SMT, CAPACITOR, PASSIVE, CERAMIC, MLCC")
    (attr smd)
    (fp_text reference "C29" (at 1.85 1.2) (layer "F.SilkS")
        (effects (font (size 0.7 0.7) (thickness 0.15)))
    )
    (fp_text value "C_100n_0402" (at 0 1.17) (layer "F.Fab") hide
        (effects (font (size 1 1) (thickness 0.15)))
    )
    (fp_text user "${REFERENCE}" (at 0 0) (layer "F.Fab")
        (effects (font (size 0.7 0.7) (thickness 0.15)))
    )
    (fp_text user "License: Apache-2.0" (at -0.939 5.799 180) (layer "F.Fab") hide
        (effects (font (size 0.7 0.7) (thickness 0.15)) (justify left bottom))
    )
    (fp_text user "Author: Antmicro" (at -0.939 3.399 180) (layer "F.Fab") hide
        (effects (font (size 0.7 0.7) (thickness 0.15)) (justify left bottom))
    )
    (fp_rect (start -0.925 -0.47) (end 0.925 0.47)
      (stroke (width 0.05) (type default)) (fill none) (layer "F.CrtYd"))
    (fp_line (start -0.494 -0.25) (end 0.504 -0.25)
      (stroke (width 0.15) (type solid)) (layer "F.Fab"))
    (fp_line (start -0.494 0.248) (end -0.494 -0.25)
      (stroke (width 0.15) (type solid)) (layer "F.Fab"))
    (fp_line (start 0.504 -0.25) (end 0.504 0.248)
      (stroke (width 0.15) (type solid)) (layer "F.Fab"))
    (fp_line (start 0.504 0.248) (end -0.494 0.248)
      (stroke (width 0.15) (type solid)) (layer "F.Fab"))
    (pad "1" smd roundrect (at -0.48 0 180) (size 0.59 0.64) (layers "F.Cu" "F.Paste" "F.Mask") (roundrect_rratio 0.25)
      (net 1 "VCC3V3") (pintype "passive"))
    (pad "2" smd roundrect (at 0.48 0 180) (size 0.59 0.64) (layers "F.Cu" "F.Paste" "F.Mask") (roundrect_rratio 0.25)
      (net 4 "GND") (pintype "passive"))
  )
	(footprint "antmicro-footprints:C_0402_1005Metric" (layer "F.Cu")
    (at 110.05 84.45 -90)
    (descr "Capacitor SMD 0402")
    (tags "capacitor SMD 0402")
    (property "Author" "Antmicro")
    (property "Dielectric" "X5R")
    (property "License" "Apache-2.0")
    (property "MPN" "GRM155R61H104KE14D")
    (property "Manufacturer" "Murata")
    (property "Sheetfile" "pow-cycl-curr-meas.kicad_sch")
    (property "Sheetname" "Power Cycling & Current Measurement")
    (property "Val" "100n")
    (property "Voltage" "50V")
    (property "ki_description" "SMD Multilayer Ceramic Capacitor, 0.1 µF, 50 V, 0402 [1005 Metric], ± 10%, X5R, GRM Series")
    (property "ki_keywords" "0402, SMT, CAPACITOR, PASSIVE, CERAMIC, MLCC")
    (attr smd)
    (fp_text reference "C28" (at 1.95 0.6 -90) (layer "F.SilkS")
        (effects (font (size 0.7 0.7) (thickness 0.15)) (justify left bottom))
    )
    (fp_text value "C_100n_0402" (at -1.022927 2.155213 -90) (layer "F.Fab")
        (effects (font (size 0.7 0.7) (thickness 0.15)) (justify left bottom))
    )
    (fp_text user "License: Apache-2.0" (at -0.939 5.799 -90) (layer "F.Fab") hide
        (effects (font (size 0.7 0.7) (thickness 0.15)) (justify left bottom))
    )
    (fp_text user "${REFERENCE}" (at -0.939 4.599 -90) (layer "F.Fab") hide
        (effects (font (size 0.7 0.7) (thickness 0.15)) (justify left bottom))
    )
    (fp_text user "Author: Antmicro" (at -0.939 3.399 -90) (layer "F.Fab") hide
        (effects (font (size 0.7 0.7) (thickness 0.15)) (justify left bottom))
    )
    (fp_rect (start -0.925 -0.47) (end 0.925 0.47)
      (stroke (width 0.05) (type default)) (fill none) (layer "F.CrtYd"))
    (fp_line (start -0.494 -0.25) (end 0.504 -0.25)
      (stroke (width 0.15) (type solid)) (layer "F.Fab"))
    (fp_line (start -0.494 0.248) (end -0.494 -0.25)
      (stroke (width 0.15) (type solid)) (layer "F.Fab"))
    (fp_line (start 0.504 -0.25) (end 0.504 0.248)
      (stroke (width 0.15) (type solid)) (layer "F.Fab"))
    (fp_line (start 0.504 0.248) (end -0.494 0.248)
      (stroke (width 0.15) (type solid)) (layer "F.Fab"))
    (pad "1" smd roundrect (at -0.48 0 270) (size 0.59 0.64) (layers "F.Cu" "F.Paste" "F.Mask") (roundrect_rratio 0.25)
      (net 1 "VCC3V3") (pintype "passive"))
    (pad "2" smd roundrect (at 0.48 0 270) (size 0.59 0.64) (layers "F.Cu" "F.Paste" "F.Mask") (roundrect_rratio 0.25)
      (net 4 "GND") (pintype "passive"))
  )
	(footprint "antmicro-footprints:TSOT23-6" (layer "F.Cu")
    (at 98.55 91)
    (property "Author" "Antmicro")
    (property "License" "Apache-2.0")
    (property "MPN" "AP62301WU-7")
    (property "Manufacturer" "Diodes Incorporated")
    (property "Sheetfile" "daughterboard-supply.kicad_sch")
    (property "Sheetname" "daughterboard-supply")
    (property "ki_description" "DC-DC Switching Synchronous Buck Regulator, Adjustable, 4.2V-18Vin, 0.8V-7V/3A out, TSOT-26-6")
    (property "ki_keywords" "SMT, PMIC, IC, VOLTAGE")
    (attr smd)
    (fp_text reference "U15" (at -1.15 3.75 90) (layer "F.SilkS")
        (effects (font (size 0.7 0.7) (thickness 0.15)) (justify left bottom))
    )
    (fp_text value "AP62301_TSOT" (at 0 2.6) (layer "F.Fab")
        (effects (font (size 0.7 0.7) (thickness 0.15)) (justify left bottom))
    )
    (fp_text user "Author: Antmicro" (at -1.93 5) (layer "F.Fab") hide
        (effects (font (size 0.7 0.7) (thickness 0.15)) (justify left bottom))
    )
    (fp_text user "${REFERENCE}" (at -1.93 3.8) (layer "F.Fab") hide
        (effects (font (size 0.7 0.7) (thickness 0.15)) (justify left bottom))
    )
    (fp_text user "License: Apache-2.0" (at -1.93 6.199) (layer "F.Fab") hide
        (effects (font (size 0.7 0.7) (thickness 0.15)) (justify left bottom))
    )
    (fp_line (start -1 -1.5) (end -1 -1.375)
      (stroke (width 0.15) (type solid)) (layer "F.SilkS"))
    (fp_line (start -1 1.55) (end -1 1.4)
      (stroke (width 0.15) (type solid)) (layer "F.SilkS"))
    (fp_line (start 1 -1.497) (end -1 -1.5)
      (stroke (width 0.15) (type solid)) (layer "F.SilkS"))
    (fp_line (start 1 -1.497) (end 1 -1.375)
      (stroke (width 0.15) (type solid)) (layer "F.SilkS"))
    (fp_line (start 1 1.55) (end -1 1.55)
      (stroke (width 0.15) (type solid)) (layer "F.SilkS"))
    (fp_line (start 1 1.55) (end 1 1.4)
      (stroke (width 0.15) (type solid)) (layer "F.SilkS"))
    (fp_circle (center -1.44 -1.5) (end -1.39 -1.5)
      (stroke (width 0.15) (type solid)) (fill solid) (layer "F.SilkS"))
    (fp_rect (start 1.93 -1.7) (end -1.93 1.7)
      (stroke (width 0.05) (type solid)) (fill none) (layer "F.CrtYd"))
    (fp_line (start -0.45 -1.521) (end -0.876 -1.096)
      (stroke (width 0.15) (type solid)) (layer "F.Fab"))
    (fp_rect (start 0.875 1.528) (end -0.875 -1.525)
      (stroke (width 0.15) (type solid)) (fill none) (layer "F.Fab"))
    (pad "1" smd rect (at -1.301 -0.947 270) (size 0.7 1.2) (layers "F.Cu" "F.Paste" "F.Mask")
      (net 4 "GND") (pinfunction "GND") (pintype "power_in"))
    (pad "2" smd rect (at -1.301 0.004 270) (size 0.7 1.2) (layers "F.Cu" "F.Paste" "F.Mask")
      (net 13 "Net-(U15-SW)") (pinfunction "SW") (pintype "power_out"))
    (pad "3" smd rect (at -1.301 0.954 270) (size 0.7 1.2) (layers "F.Cu" "F.Paste" "F.Mask")
      (net 11 "VCC12V0") (pinfunction "VIN") (pintype "power_in"))
    (pad "4" smd rect (at 1.299 0.954 270) (size 0.7 1.2) (layers "F.Cu" "F.Paste" "F.Mask")
      (net 111 "Net-(U15-FB)") (pinfunction "FB") (pintype "input"))
    (pad "5" smd rect (at 1.299 0.004 270) (size 0.7 1.2) (layers "F.Cu" "F.Paste" "F.Mask")
      (net 165 "unconnected-(U15-EN-Pad5)") (pinfunction "EN") (pintype "input+no_connect"))
    (pad "6" smd rect (at 1.299 -0.947 270) (size 0.7 1.2) (layers "F.Cu" "F.Paste" "F.Mask")
      (net 12 "Net-(U15-BST)") (pinfunction "BST") (pintype "output"))
  )
	(footprint "antmicro-footprints:R_0402_1005Metric" (layer "F.Cu")
    (at 109.6 86.8)
    (descr "Resistor SMD 0402")
    (tags "resistor SMD 0402")
    (property "Author" "Antmicro")
    (property "License" "Apache-2.0")
    (property "MPN" "CR0402-FX-1002GLF")
    (property "Manufacturer" "Bourns")
    (property "Sheetfile" "power-switch.kicad_sch")
    (property "Sheetname" "Power switch 1")
    (property "Tolerance" "1%")
    (property "Val" "10k")
    (property "ki_description" "SMD Chip Resistor, 10 kohm, ± 1%, 62.5 mW, 0402 [1005 Metric], Thick Film, General Purpose")
    (property "ki_keywords" "0402, SMT, RESISTOR, PASSIVE")
    (attr smd)
    (fp_text reference "R20" (at -3.05 0.45) (layer "F.SilkS")
        (effects (font (size 0.7 0.7) (thickness 0.15)) (justify left bottom))
    )
    (fp_text value "R_10k_0402" (at -1.011843 1.772047) (layer "F.Fab")
        (effects (font (size 0.7 0.7) (thickness 0.15)) (justify left bottom))
    )
    (fp_text user "License: Apache-2.0" (at -0.95 5.169) (layer "F.Fab") hide
        (effects (font (size 0.7 0.7) (thickness 0.15)) (justify left bottom))
    )
    (fp_text user "${REFERENCE}" (at -0.95 3.168) (layer "F.Fab") hide
        (effects (font (size 0.7 0.7) (thickness 0.15)) (justify left bottom))
    )
    (fp_text user "Author: Antmicro" (at -0.95 4.169) (layer "F.Fab") hide
        (effects (font (size 0.7 0.7) (thickness 0.15)) (justify left bottom))
    )
    (fp_rect (start -0.925 -0.47) (end 0.925 0.47)
      (stroke (width 0.05) (type default)) (fill none) (layer "F.CrtYd"))
    (fp_rect (start -0.5 -0.25) (end 0.5 0.25)
      (stroke (width 0.15) (type solid)) (fill none) (layer "F.Fab"))
    (pad "1" smd roundrect (at -0.48 0) (size 0.59 0.64) (layers "F.Cu" "F.Paste" "F.Mask") (roundrect_rratio 0.25)
      (net 1 "VCC3V3") (pintype "passive"))
    (pad "2" smd roundrect (at 0.48 0) (size 0.59 0.64) (layers "F.Cu" "F.Paste" "F.Mask") (roundrect_rratio 0.25)
      (net 23 "/Power Cycling & Current Measurement/PC_1") (pintype "passive"))
  )
	(footprint "antmicro-footprints:C_0402_1005Metric" (layer "F.Cu")
    (at 181.2 115.3)
    (descr "Capacitor SMD 0402")
    (tags "capacitor SMD 0402")
    (property "Author" "Antmicro")
    (property "Dielectric" "X5R")
    (property "License" "Apache-2.0")
    (property "MPN" "GRM155R61H104KE14D")
    (property "Manufacturer" "Murata")
    (property "Sheetfile" "ftdi-module.kicad_sch")
    (property "Sheetname" "FTDI")
    (property "Val" "100n")
    (property "Voltage" "50V")
    (property "ki_description" "SMD Multilayer Ceramic Capacitor, 0.1 µF, 50 V, 0402 [1005 Metric], ± 10%, X5R, GRM Series")
    (property "ki_keywords" "0402, SMT, CAPACITOR, PASSIVE, CERAMIC, MLCC")
    (attr smd)
    (fp_text reference "C17" (at -3 0.5) (layer "F.SilkS")
        (effects (font (size 0.7 0.7) (thickness 0.15)) (justify left bottom))
    )
    (fp_text value "C_100n_0402" (at -1.022927 2.155213) (layer "F.Fab")
        (effects (font (size 0.7 0.7) (thickness 0.15)) (justify left bottom))
    )
    (fp_text user "Author: Antmicro" (at -0.939 3.399) (layer "F.Fab") hide
        (effects (font (size 0.7 0.7) (thickness 0.15)) (justify left bottom))
    )
    (fp_text user "License: Apache-2.0" (at -0.939 5.799) (layer "F.Fab") hide
        (effects (font (size 0.7 0.7) (thickness 0.15)) (justify left bottom))
    )
    (fp_text user "${REFERENCE}" (at -0.939 4.599) (layer "F.Fab") hide
        (effects (font (size 0.7 0.7) (thickness 0.15)) (justify left bottom))
    )
    (fp_rect (start -0.925 -0.47) (end 0.925 0.47)
      (stroke (width 0.05) (type default)) (fill none) (layer "F.CrtYd"))
    (fp_line (start -0.494 -0.25) (end 0.504 -0.25)
      (stroke (width 0.15) (type solid)) (layer "F.Fab"))
    (fp_line (start -0.494 0.248) (end -0.494 -0.25)
      (stroke (width 0.15) (type solid)) (layer "F.Fab"))
    (fp_line (start 0.504 -0.25) (end 0.504 0.248)
      (stroke (width 0.15) (type solid)) (layer "F.Fab"))
    (fp_line (start 0.504 0.248) (end -0.494 0.248)
      (stroke (width 0.15) (type solid)) (layer "F.Fab"))
    (pad "1" smd roundrect (at -0.48 0) (size 0.59 0.64) (layers "F.Cu" "F.Paste" "F.Mask") (roundrect_rratio 0.25)
      (net 77 "GNDD") (pintype "passive"))
    (pad "2" smd roundrect (at 0.48 0) (size 0.59 0.64) (layers "F.Cu" "F.Paste" "F.Mask") (roundrect_rratio 0.25)
      (net 10 "VBUS") (pintype "passive"))
  )
	(footprint "antmicro-footprints:C_0402_1005Metric" (layer "F.Cu")
    (at 155.6 102.235 90)
    (descr "Capacitor SMD 0402")
    (tags "capacitor SMD 0402")
    (property "Author" "Antmicro")
    (property "Dielectric" "")
    (property "License" "Apache-2.0")
    (property "MPN" "C1005X6S1A105K050BC")
    (property "Manufacturer" "TDK")
    (property "Sheetfile" "pow-cycl-curr-meas.kicad_sch")
    (property "Sheetname" "Power Cycling & Current Measurement")
    (property "Val" "1u")
    (property "Voltage" "")
    (property "ki_description" "SMD Multilayer Ceramic Capacitor, 1 µF, 10 V, 0402 [1005 Metric], ± 10%, X6S, C")
    (property "ki_keywords" "0402, SMT, CAPACITOR, PASSIVE, CERAMIC, MLCC")
    (attr smd)
    (fp_text reference "C22" (at 0.035 1 90) (layer "F.SilkS")
        (effects (font (size 0.7 0.7) (thickness 0.15)))
    )
    (fp_text value "C_1u_0402" (at 0 1.17 90) (layer "F.Fab") hide
        (effects (font (size 1 1) (thickness 0.15)))
    )
    (fp_text user "${REFERENCE}" (at 0 0 90) (layer "F.Fab")
        (effects (font (size 0.7 0.7) (thickness 0.15)))
    )
    (fp_text user "Author: Antmicro" (at -0.939 3.399 90) (layer "F.Fab") hide
        (effects (font (size 0.7 0.7) (thickness 0.15)) (justify left bottom))
    )
    (fp_text user "License: Apache-2.0" (at -0.939 5.799 90) (layer "F.Fab") hide
        (effects (font (size 0.7 0.7) (thickness 0.15)) (justify left bottom))
    )
    (fp_rect (start -0.925 -0.47) (end 0.925 0.47)
      (stroke (width 0.05) (type default)) (fill none) (layer "F.CrtYd"))
    (fp_line (start -0.494 -0.25) (end 0.504 -0.25)
      (stroke (width 0.15) (type solid)) (layer "F.Fab"))
    (fp_line (start -0.494 0.248) (end -0.494 -0.25)
      (stroke (width 0.15) (type solid)) (layer "F.Fab"))
    (fp_line (start 0.504 -0.25) (end 0.504 0.248)
      (stroke (width 0.15) (type solid)) (layer "F.Fab"))
    (fp_line (start 0.504 0.248) (end -0.494 0.248)
      (stroke (width 0.15) (type solid)) (layer "F.Fab"))
    (pad "1" smd roundrect (at -0.48 0 90) (size 0.59 0.64) (layers "F.Cu" "F.Paste" "F.Mask") (roundrect_rratio 0.25)
      (net 4 "GND") (pintype "passive"))
    (pad "2" smd roundrect (at 0.48 0 90) (size 0.59 0.64) (layers "F.Cu" "F.Paste" "F.Mask") (roundrect_rratio 0.25)
      (net 1 "VCC3V3") (pintype "passive"))
  )
)
